# S9S_MB_2U (Grand Teton) — schematic netlist excerpt (pin names and nets, part order shuffled) for the footprints in the layout excerpt that follows; sources: Cadence DE-HDL packaged netlist, KiCad conversion of 03242023_DA0F0TMBIJ0_F0T_Motherboard_J_brd_V01_OCP.brd

PU25_P1_6  ISL99390FRZTR5935  ISL99390FRZ-TR5935 IC  pkg QFN21_6X5XB  page 287
  VOS  = PVCCIN_CPU1_VOS6
  AGND  = GND
  VCC  = PVCCIN_CPU1_VDD6
  PVCC  = PVCCIN_CPU1_PVCC
  PGND1  = GND
  GL1  = NC
  PGND2  = GND
  SW  = SW_PVCCIN_CPU1_SW6
  VIN1  = SW_P12V_PVCCIN_CPU1_FLT
  VIN2  = SW_P12V_PVCCIN_CPU1_FLT
  DNC  = NC
  PHASE  = SW_PVCCIN_CPU1_BOOTR6
  BOOT  = SW_PVCCIN_CPU1_BOOT6
  PWM  = PVCCIN_CPU1_PWM6
  EN  = PVCCIN_CPU1_VDD6
  TOUT_FLT  = PVCCIN_CPU1_ATSEN
  LSET  = PVCCIN_CPU1_LSET6
  IOUT  = PVCCIN_CPU1_IMON6
  REFIN  = PVCCIN_CPU1_VREF
  PGND3  = GND
  GL2  = NC

(kicad_pcb
	(version 20260206)
	(generator "pcbnew")
	(generator_version "10.0")
	(general
		(thickness 1.6)
		(legacy_teardrops no)
	)
	(paper "A4")
	(title_block
		(title "03242023_DA0F0TMBIJ0_F0T_Motherboard_J_brd_V01_OCP.brd")
		(comment 1 "Grand Teton / footprints 2056-2056 of 6105")
	)
	(layers
		(0 "F.Cu" signal "TOP")
		(4 "In1.Cu" signal "GND")
		(6 "In2.Cu" signal "IN1")
		(8 "In3.Cu" signal "GND1")
		(10 "In4.Cu" signal "IN2")
		(12 "In5.Cu" signal "GND2")
		(14 "In6.Cu" signal "IN3")
		(16 "In7.Cu" signal "GND3")
		(18 "In8.Cu" signal "VCC")
		(20 "In9.Cu" signal "VCC1")
		(22 "In10.Cu" signal "GND4")
		(24 "In11.Cu" signal "IN4")
		(26 "In12.Cu" signal "GND5")
		(28 "In13.Cu" signal "IN5")
		(30 "In14.Cu" signal "GND6")
		(32 "In15.Cu" signal "IN6")
		(34 "In16.Cu" signal "GND7")
		(2 "B.Cu" signal "BOTTOM")
		(9 "F.Adhes" user "F.Adhesive")
		(11 "B.Adhes" user "B.Adhesive")
		(13 "F.Paste" user "Package Geometry/Pastemask Top")
		(15 "B.Paste" user "Package Geometry/Pastemask Bottom")
		(5 "F.SilkS" user "Ref Des/Silkscreen Top")
		(7 "B.SilkS" user "Ref Des/Silkscreen Bottom")
		(1 "F.Mask" user "Board Geometry/Soldermask Top")
		(3 "B.Mask" user "Board Geometry/Soldermask Bottom")
		(17 "Dwgs.User" user "User.Drawings")
		(19 "Cmts.User" user "User.Comments")
		(21 "Eco1.User" user "User.Eco1")
		(23 "Eco2.User" user "User.Eco2")
		(25 "Edge.Cuts" user "Board Geometry/Outline")
		(27 "Margin" user)
		(31 "F.CrtYd" user "Package Geometry/Place Bound Top")
		(29 "B.CrtYd" user "Package Geometry/Place Bound Bottom")
		(35 "F.Fab" user "Ref Des/Assembly Top")
		(33 "B.Fab" user "Ref Des/Assembly Bottom")
	)
	(footprint ""
		(layer "F.Cu")
		(at 88.837262 -337.126326)
		(property "Reference" "PU25_P1_6"
			(at -2.0955 -6.41985 0)
			(unlocked yes)
			(layer "F.SilkS")
			(effects
				(font
					(size 0.7874 0.5842)
					(thickness 0.1524)
				)
				(justify left)
			)
		)
		(property "Value" ""
			(at 0 0 0)
			(layer "F.Fab")
			(effects
				(font
					(size 1.27 1.27)
				)
			)
		)
		(duplicate_pad_numbers_are_jumpers no)
		(fp_line
			(start -2.500122 -2.999994)
			(end -2.24409 -2.999994)
			(stroke
				(width 0.1524)
				(type default)
			)
			(layer "F.SilkS")
		)
		(fp_line
			(start -2.500122 -2.529078)
			(end -2.500122 -2.999994)
			(stroke
				(width 0.1524)
				(type default)
			)
			(layer "F.SilkS")
		)
		(fp_line
			(start -2.500122 0.6604)
			(end -2.500122 0.229108)
			(stroke
				(width 0.1524)
				(type default)
			)
			(layer "F.SilkS")
		)
		(fp_line
			(start -2.500122 2.999994)
			(end -2.500122 2.339594)
			(stroke
				(width 0.1524)
				(type default)
			)
			(layer "F.SilkS")
		)
		(fp_line
			(start -2.2987 2.999994)
			(end -2.500122 2.999994)
			(stroke
				(width 0.1524)
				(type default)
			)
			(layer "F.SilkS")
		)
		(fp_line
			(start 2.31394 -2.999994)
			(end 2.500122 -2.999994)
			(stroke
				(width 0.1524)
				(type default)
			)
			(layer "F.SilkS")
		)
		(fp_line
			(start 2.500122 -2.999994)
			(end 2.500122 -2.44348)
			(stroke
				(width 0.1524)
				(type default)
			)
			(layer "F.SilkS")
		)
		(fp_line
			(start 2.500122 2.339594)
			(end 2.500122 2.999994)
			(stroke
				(width 0.1524)
				(type default)
			)
			(layer "F.SilkS")
		)
		(fp_line
			(start 2.500122 2.999994)
			(end 2.2987 2.999994)
			(stroke
				(width 0.1524)
				(type default)
			)
			(layer "F.SilkS")
		)
		(fp_poly
			(pts
				(xy -2.209546 -3.690112) (xy -2.717546 -2.674112) (xy -3.225546 -3.690112)
			)
			(stroke
				(width 0)
				(type default)
			)
			(fill yes)
			(layer "F.SilkS")
		)
		(fp_line
			(start -2.500122 -2.999994)
			(end 2.500122 -2.999994)
			(stroke
				(width 0.1)
				(type default)
			)
			(layer "F.Fab")
		)
		(fp_line
			(start -2.500122 2.999994)
			(end -2.500122 -2.999994)
			(stroke
				(width 0.1)
				(type default)
			)
			(layer "F.Fab")
		)
		(fp_line
			(start 2.500122 -2.999994)
			(end 2.500122 2.999994)
			(stroke
				(width 0.1)
				(type default)
			)
			(layer "F.Fab")
		)
		(fp_line
			(start 2.500122 2.999994)
			(end -2.500122 2.999994)
			(stroke
				(width 0.1)
				(type default)
			)
			(layer "F.Fab")
		)
		(fp_poly
			(pts
				(xy -4.218432 -2.783078) (xy -4.218432 -1.767078) (xy -3.202432 -2.275078)
			)
			(stroke
				(width 0)
				(type default)
			)
			(fill yes)
			(layer "F.Fab")
		)
		(pad "1" smd rect
			(at -2.400046 -2.275078 90)
			(size 0.2286 0.6096)
			(layers "F.Cu" "F.Mask" "F.Paste")
			(net "PVCCIN_CPU1_VOS6")
		)
		(pad "2" smd rect
			(at -2.400046 -1.82499 90)
			(size 0.2286 0.6096)
			(layers "F.Cu" "F.Mask" "F.Paste")
			(net "GND")
		)
		(pad "3" smd rect
			(at -2.400046 -1.374902 90)
			(size 0.2286 0.6096)
			(layers "F.Cu" "F.Mask" "F.Paste")
			(net "PVCCIN_CPU1_VDD6")
		)
		(pad "4" smd rect
			(at -2.400046 -0.925068 90)
			(size 0.2286 0.6096)
			(layers "F.Cu" "F.Mask" "F.Paste")
			(net "PVCCIN_CPU1_PVCC")
		)
		(pad "5" smd rect
			(at -2.400046 -0.47498 90)
			(size 0.2286 0.6096)
			(layers "F.Cu" "F.Mask" "F.Paste")
			(net "GND")
		)
		(pad "6" smd rect
			(at -2.400046 -0.024892 90)
			(size 0.2286 0.6096)
			(layers "F.Cu" "F.Mask" "F.Paste")
			(net "Net_8535")
		)
		(pad "7_9-20_24" smd circle
			(at 0 1.150112 90)
			(size 0 0)
			(layers "F.Cu" "F.Mask" "F.Paste")
			(net "GND")
		)
		(pad "10_19" smd rect
			(at 0 2.899918 90)
			(size 0.6096 4.318)
			(layers "F.Cu" "F.Mask" "F.Paste")
			(net "SW_PVCCIN_CPU1_SW6")
		)
		(pad "25_29" smd rect
			(at 1.549908 -1.279906 270)
			(size 2.0574 2.3114)
			(layers "F.Cu" "F.Mask" "F.Paste")
			(net "SW_P12V_PVCCIN_CPU1_FLT")
		)
		(pad "30" smd rect
			(at 2.05994 -2.899918)
			(size 0.2286 0.6096)
			(layers "F.Cu" "F.Mask" "F.Paste")
			(net "SW_P12V_PVCCIN_CPU1_FLT")
		)
		(pad "31" smd rect
			(at 1.610106 -2.899918)
			(size 0.2286 0.6096)
			(layers "F.Cu" "F.Mask" "F.Paste")
			(net "Net_8536")
		)
		(pad "32" smd rect
			(at 1.160018 -2.899918)
			(size 0.2286 0.6096)
			(layers "F.Cu" "F.Mask" "F.Paste")
			(net "SW_PVCCIN_CPU1_BOOTR6")
		)
		(pad "33" smd rect
			(at 0.70993 -2.899918)
			(size 0.2286 0.6096)
			(layers "F.Cu" "F.Mask" "F.Paste")
			(net "SW_PVCCIN_CPU1_BOOT6")
		)
		(pad "34" smd rect
			(at 0.260096 -2.899918)
			(size 0.2286 0.6096)
			(layers "F.Cu" "F.Mask" "F.Paste")
			(net "PVCCIN_CPU1_PWM6")
		)
		(pad "35" smd rect
			(at -0.189992 -2.899918)
			(size 0.2286 0.6096)
			(layers "F.Cu" "F.Mask" "F.Paste")
			(net "PVCCIN_CPU1_VDD6")
		)
		(pad "36" smd rect
			(at -0.64008 -2.899918)
			(size 0.2286 0.6096)
			(layers "F.Cu" "F.Mask" "F.Paste")
			(net "PVCCIN_CPU1_ATSEN")
		)
		(pad "37" smd rect
			(at -1.089914 -2.899918)
			(size 0.2286 0.6096)
			(layers "F.Cu" "F.Mask" "F.Paste")
			(net "PVCCIN_CPU1_LSET6")
		)
		(pad "38" smd rect
			(at -1.540002 -2.899918)
			(size 0.2286 0.6096)
			(layers "F.Cu" "F.Mask" "F.Paste")
			(net "PVCCIN_CPU1_IMON6")
		)
		(pad "39" smd rect
			(at -1.99009 -2.899918)
			(size 0.2286 0.6096)
			(layers "F.Cu" "F.Mask" "F.Paste")
			(net "PVCCIN_CPU1_VREF")
		)
		(pad "40" smd rect
			(at -0.87503 -1.27508)
			(size 1.7526 1.9558)
			(layers "F.Cu" "F.Mask" "F.Paste")
			(net "GND")
		)
		(pad "41" smd rect
			(at -1.525016 0.249936 270)
			(size 0.3048 0.4572)
			(layers "F.Cu" "F.Mask" "F.Paste")
			(net "Net_8534")
		)
		(zone
			(layer "F.Cu")
			(hatch none 0.5)
			(connect_pads
				(clearance 0)
			)
			(min_thickness 0.25)
			(keepout
				(tracks not_allowed)
				(vias allowed)
				(pads allowed)
				(copperpour not_allowed)
				(footprints allowed)
			)
			(placement
				(enabled no)
				(sheetname "")
			)
			(fill
				(thermal_gap 0.5)
				(thermal_bridge_width 0.5)
				(island_removal_mode 0)
			)
			(polygon
				(pts
					(xy 86.33714 -334.126332) (xy 86.33714 -334.875632) (xy 91.337384 -334.875632) (xy 91.337384 -334.126332)
					(xy 91.047062 -334.126332) (xy 91.047062 -334.582008) (xy 86.627462 -334.582008) (xy 86.627462 -334.126332)
				)
			)
		)
		(zone
			(layer "F.Cu")
			(hatch none 0.5)
			(connect_pads
				(clearance 0)
			)
			(min_thickness 0.25)
			(keepout
				(tracks not_allowed)
				(vias allowed)
				(pads allowed)
				(copperpour not_allowed)
				(footprints allowed)
			)
			(placement
				(enabled no)
				(sheetname "")
			)
			(fill
				(thermal_gap 0.5)
				(thermal_bridge_width 0.5)
				(island_removal_mode 0)
			)
			(polygon
				(pts
					(xy 86.792816 -337.464908) (xy 87.035132 -337.464908) (xy 87.035132 -337.372706) (xy 87.82812 -337.372706)
					(xy 87.82812 -337.035648) (xy 87.88654 -337.035648) (xy 87.88654 -336.377026) (xy 86.33714 -336.377026)
					(xy 86.33714 -336.833718) (xy 87.032846 -336.833718) (xy 87.032846 -336.67319) (xy 87.591646 -336.67319)
					(xy 87.591646 -337.07959) (xy 87.032846 -337.07959) (xy 87.032846 -336.859118) (xy 86.33714 -336.859118)
					(xy 86.33714 -336.986118) (xy 86.792816 -336.986118)
				)
			)
		)
	)
)
